(kicad_pcb
	(version 20240108)
	(generator "pcbnew")
	(generator_version "8.0")
	(general
		(thickness 1.62)
		(legacy_teardrops no)
	)
	(paper "A4")
	(title_block
		(title "Jetson Orin Baseboard")
		(date "2025-03-12")
		(rev "1.3.4")
		(company "Antmicro Ltd")
		(comment 1 "www.antmicro.com")
		(comment 9 "footprints 227-230 of 677")
	)
	(layers
		(0 "F.Cu" signal)
		(1 "In1.Cu" signal)
		(2 "In2.Cu" signal)
		(3 "In3.Cu" signal)
		(4 "In4.Cu" jumper)
		(5 "In5.Cu" signal)
		(6 "In6.Cu" signal)
		(31 "B.Cu" signal)
		(32 "B.Adhes" user "B.Adhesive")
		(33 "F.Adhes" user "F.Adhesive")
		(34 "B.Paste" user)
		(35 "F.Paste" user)
		(36 "B.SilkS" user "B.Silkscreen")
		(37 "F.SilkS" user "F.Silkscreen")
		(38 "B.Mask" user)
		(39 "F.Mask" user)
		(40 "Dwgs.User" user "User.Drawings")
		(41 "Cmts.User" user "User.Comments")
		(42 "Eco1.User" user "User.Eco1")
		(43 "Eco2.User" user "User.Eco2")
		(44 "Edge.Cuts" user)
		(45 "Margin" user)
		(46 "B.CrtYd" user "B.Courtyard")
		(47 "F.CrtYd" user "F.Courtyard")
		(48 "B.Fab" user)
		(49 "F.Fab" user)
	)
	(footprint "antmicro-footprints:R_Array_4x0201_Panasonic_EXB18V"
		(layer "F.Cu")
		(at 97.21 104.25 -135)
		(property "Reference" "R50"
			(at 1.046518 -1.583919 45)
			(layer "F.SilkS")
			(effects
				(font
					(size 0.7 0.7)
					(thickness 0.15)
				)
				(justify left bottom)
			)
		)
		(property "Value" "R_4x0R_0201_array"
			(at -1.1 1.8 -135)
			(layer "F.Fab")
			(effects
				(font
					(size 0.7 0.7)
					(thickness 0.15)
				)
				(justify left bottom)
			)
		)
		(property "Footprint" "antmicro-footprints:R_Array_4x0201_Panasonic_EXB18V"
			(at 0 0 -135)
			(layer "F.Fab")
			(hide yes)
			(effects
				(font
					(size 1.27 1.27)
					(thickness 0.15)
				)
			)
		)
		(property "Datasheet" "http://industrial.panasonic.com/cdbs/www-data/pdf/AOC0000/AOC0000C14.pdf"
			(at 0 0 -135)
			(layer "F.Fab")
			(hide yes)
			(effects
				(font
					(size 1.27 1.27)
					(thickness 0.15)
				)
			)
		)
		(property "Author" "Antmicro"
			(at 92.231968 246.703732 0)
			(layer "F.Fab")
			(hide yes)
			(effects
				(font
					(size 1 1)
					(thickness 0.15)
				)
			)
		)
		(property "License" "Apache-2.0"
			(at 92.231968 246.703732 0)
			(layer "F.Fab")
			(hide yes)
			(effects
				(font
					(size 1 1)
					(thickness 0.15)
				)
			)
		)
		(property "MPN" "EXB-18VR000X"
			(at 92.231968 246.703732 0)
			(layer "F.Fab")
			(hide yes)
			(effects
				(font
					(size 1 1)
					(thickness 0.15)
				)
			)
		)
		(property "Manufacturer" "Panasonic"
			(at 92.231968 246.703732 0)
			(layer "F.Fab")
			(hide yes)
			(effects
				(font
					(size 1 1)
					(thickness 0.15)
				)
			)
		)
		(property "Val" "4x0R_0201"
			(at 92.231968 246.703732 0)
			(layer "F.Fab")
			(hide yes)
			(effects
				(font
					(size 1 1)
					(thickness 0.15)
				)
			)
		)
		(sheetname "CSI")
		(sheetfile "csi.kicad_sch")
		(attr smd)
		(fp_line
			(start 0.799999 -0.45)
			(end 0.799999 0.45)
			(stroke
				(width 0.12)
				(type solid)
			)
			(layer "F.SilkS")
		)
		(fp_line
			(start -0.799999 -0.45)
			(end -0.799999 0.45)
			(stroke
				(width 0.12)
				(type solid)
			)
			(layer "F.SilkS")
		)
		(fp_poly
			(pts
				(xy -0.897999 -0.66) (xy 0.897999 -0.66) (xy 0.897999 0.65) (xy -0.897999 0.65)
			)
			(stroke
				(width 0.05)
				(type solid)
			)
			(fill none)
			(layer "F.CrtYd")
		)
		(fp_text user "${REFERENCE}"
			(at -1.051 3.2 -135)
			(layer "F.Fab")
			(hide yes)
			(effects
				(font
					(size 0.7 0.7)
					(thickness 0.15)
				)
				(justify left bottom)
			)
		)
		(fp_text user "License: Apache-2.0"
			(at -1.051 6 -135)
			(layer "F.Fab")
			(hide yes)
			(effects
				(font
					(size 0.7 0.7)
					(thickness 0.15)
				)
				(justify left bottom)
			)
		)
		(fp_text user "Author: Antmicro"
			(at -1.051 4.599 -135)
			(layer "F.Fab")
			(hide yes)
			(effects
				(font
					(size 0.7 0.7)
					(thickness 0.15)
				)
				(justify left bottom)
			)
		)
		(pad "1" smd roundrect
			(at -0.6 0.298 225)
			(size 0.2 0.4)
			(layers "F.Cu" "F.Paste" "F.Mask")
			(roundrect_rratio 0.25)
			(net 320 "/CSI/SDA_CAM0")
			(pinfunction "R1.1")
			(pintype "passive")
		)
		(pad "2" smd roundrect
			(at -0.202 0.298 225)
			(size 0.2 0.4)
			(layers "F.Cu" "F.Paste" "F.Mask")
			(roundrect_rratio 0.25)
			(net 323 "/CSI/SCL_CAM0")
			(pinfunction "R2.1")
			(pintype "passive")
		)
		(pad "3" smd roundrect
			(at 0.2 0.298 225)
			(size 0.2 0.4)
			(layers "F.Cu" "F.Paste" "F.Mask")
			(roundrect_rratio 0.25)
			(net 329 "/CSI/SDA_CAM1")
			(pinfunction "R3.1")
			(pintype "passive")
		)
		(pad "4" smd roundrect
			(at 0.598 0.298 225)
			(size 0.2 0.4)
			(layers "F.Cu" "F.Paste" "F.Mask")
			(roundrect_rratio 0.25)
			(net 330 "/CSI/SCL_CAM1")
			(pinfunction "R4.1")
			(pintype "passive")
		)
		(pad "5" smd roundrect
			(at 0.598 -0.3 225)
			(size 0.2 0.4)
			(layers "F.Cu" "F.Paste" "F.Mask")
			(roundrect_rratio 0.25)
			(net 563 "Net-(R50-R4.2)")
			(pinfunction "R4.2")
			(pintype "passive")
		)
		(pad "6" smd roundrect
			(at 0.199999 -0.3 225)
			(size 0.2 0.4)
			(layers "F.Cu" "F.Paste" "F.Mask")
			(roundrect_rratio 0.25)
			(net 560 "Net-(R50-R3.2)")
			(pinfunction "R3.2")
			(pintype "passive")
		)
		(pad "7" smd roundrect
			(at -0.202001 -0.3 225)
			(size 0.2 0.4)
			(layers "F.Cu" "F.Paste" "F.Mask")
			(roundrect_rratio 0.25)
			(net 559 "Net-(R50-R2.2)")
			(pinfunction "R2.2")
			(pintype "passive")
		)
		(pad "8" smd roundrect
			(at -0.6 -0.3 225)
			(size 0.2 0.4)
			(layers "F.Cu" "F.Paste" "F.Mask")
			(roundrect_rratio 0.25)
			(net 554 "Net-(R50-R1.2)")
			(pinfunction "R1.2")
			(pintype "passive")
		)
	)
	(footprint "antmicro-footprints:R_0402_1005Metric"
		(layer "F.Cu")
		(at 66.21 98.93 180)
		(descr "Resistor SMD 0402")
		(tags "resistor SMD 0402")
		(property "Reference" "R170"
			(at -1.14 -2.295 0)
			(layer "F.SilkS")
			(effects
				(font
					(size 0.7 0.7)
					(thickness 0.15)
				)
				(justify right bottom)
			)
		)
		(property "Value" "R_73k2_0402"
			(at -1.011843 1.772047 0)
			(layer "F.Fab")
			(effects
				(font
					(size 0.7 0.7)
					(thickness 0.15)
				)
				(justify right bottom)
			)
		)
		(property "Footprint" "antmicro-footprints:R_0402_1005Metric"
			(at 0 0 180)
			(layer "F.Fab")
			(hide yes)
			(effects
				(font
					(size 1.27 1.27)
					(thickness 0.15)
				)
			)
		)
		(property "Datasheet" "https://www.bourns.com/docs/product-datasheets/cr.pdf"
			(at 0 0 180)
			(layer "F.Fab")
			(hide yes)
			(effects
				(font
					(size 1.27 1.27)
					(thickness 0.15)
				)
			)
		)
		(property "Author" "Antmicro"
			(at 132.42 197.86 0)
			(layer "F.Fab")
			(hide yes)
			(effects
				(font
					(size 1 1)
					(thickness 0.15)
				)
			)
		)
		(property "License" "Apache-2.0"
			(at 132.42 197.86 0)
			(layer "F.Fab")
			(hide yes)
			(effects
				(font
					(size 1 1)
					(thickness 0.15)
				)
			)
		)
		(property "MPN" "CR0402-FX-7322GLF"
			(at 132.42 197.86 0)
			(layer "F.Fab")
			(hide yes)
			(effects
				(font
					(size 1 1)
					(thickness 0.15)
				)
			)
		)
		(property "Manufacturer" "Bourns"
			(at 132.42 197.86 0)
			(layer "F.Fab")
			(hide yes)
			(effects
				(font
					(size 1 1)
					(thickness 0.15)
				)
			)
		)
		(property "Tolerance" "1%"
			(at 132.42 197.86 0)
			(layer "F.Fab")
			(hide yes)
			(effects
				(font
					(size 1 1)
					(thickness 0.15)
				)
			)
		)
		(property "Val" "73k2"
			(at 132.42 197.86 0)
			(layer "F.Fab")
			(hide yes)
			(effects
				(font
					(size 1 1)
					(thickness 0.15)
				)
			)
		)
		(sheetname "Supply")
		(sheetfile "supply.kicad_sch")
		(attr smd)
		(fp_rect
			(start -0.925 -0.47)
			(end 0.925 0.47)
			(stroke
				(width 0.05)
				(type default)
			)
			(fill none)
			(layer "F.CrtYd")
		)
		(fp_rect
			(start -0.5 -0.25)
			(end 0.5 0.25)
			(stroke
				(width 0.15)
				(type solid)
			)
			(fill none)
			(layer "F.Fab")
		)
		(fp_text user "License: Apache-2.0"
			(at -0.95 5.169 0)
			(layer "F.Fab")
			(hide yes)
			(effects
				(font
					(size 0.7 0.7)
					(thickness 0.15)
				)
				(justify right bottom)
			)
		)
		(fp_text user "Author: Antmicro"
			(at -0.95 4.169 0)
			(layer "F.Fab")
			(hide yes)
			(effects
				(font
					(size 0.7 0.7)
					(thickness 0.15)
				)
				(justify right bottom)
			)
		)
		(fp_text user "${REFERENCE}"
			(at -0.95 3.168 0)
			(layer "F.Fab")
			(hide yes)
			(effects
				(font
					(size 0.7 0.7)
					(thickness 0.15)
				)
				(justify right bottom)
			)
		)
		(pad "1" smd roundrect
			(at -0.48 0 180)
			(size 0.59 0.64)
			(layers "F.Cu" "F.Paste" "F.Mask")
			(roundrect_rratio 0.25)
			(net 766 "/Supply/5V_FB")
			(pintype "passive")
		)
		(pad "2" smd roundrect
			(at 0.48 0 180)
			(size 0.59 0.64)
			(layers "F.Cu" "F.Paste" "F.Mask")
			(roundrect_rratio 0.25)
			(net 761 "/Supply/5V_OUT")
			(pintype "passive")
		)
	)
	(footprint "antmicro-footprints:SW_KMR211NGLFS_SMD"
		(layer "F.Cu")
		(at 64.2 125.9)
		(property "Reference" "S4"
			(at -0.8 -1.8 0)
			(layer "F.SilkS")
			(effects
				(font
					(size 0.7 0.7)
					(thickness 0.15)
				)
				(justify left bottom)
			)
		)
		(property "Value" "SW_KMR211NGLFS_SMD"
			(at -3 3 0)
			(layer "F.Fab")
			(effects
				(font
					(size 0.7 0.7)
					(thickness 0.15)
				)
				(justify left bottom)
			)
		)
		(property "Footprint" "antmicro-footprints:SW_KMR211NGLFS_SMD"
			(at 0 0 0)
			(layer "F.Fab")
			(hide yes)
			(effects
				(font
					(size 1.27 1.27)
					(thickness 0.15)
				)
			)
		)
		(property "Datasheet" "http://www.farnell.com/datasheets/2631211.pdf"
			(at 0 0 0)
			(layer "F.Fab")
			(hide yes)
			(effects
				(font
					(size 1.27 1.27)
					(thickness 0.15)
				)
			)
		)
		(property "Author" "Antmicro"
			(at 0 0 0)
			(layer "F.Fab")
			(hide yes)
			(effects
				(font
					(size 1 1)
					(thickness 0.15)
				)
			)
		)
		(property "License" "Apache-2.0"
			(at 0 0 0)
			(layer "F.Fab")
			(hide yes)
			(effects
				(font
					(size 1 1)
					(thickness 0.15)
				)
			)
		)
		(property "MPN" "KMR211NGLFS"
			(at 0 0 0)
			(layer "F.Fab")
			(hide yes)
			(effects
				(font
					(size 1 1)
					(thickness 0.15)
				)
			)
		)
		(property "Manufacturer" "C&K"
			(at 0 0 0)
			(layer "F.Fab")
			(hide yes)
			(effects
				(font
					(size 1 1)
					(thickness 0.15)
				)
			)
		)
		(sheetname "Supply")
		(sheetfile "supply.kicad_sch")
		(attr smd)
		(fp_line
			(start -2.1 -1.6)
			(end -2.1 -1.499)
			(stroke
				(width 0.15)
				(type solid)
			)
			(layer "F.SilkS")
		)
		(fp_line
			(start -2.1 1.601)
			(end -2.1 1.48)
			(stroke
				(width 0.15)
				(type solid)
			)
			(layer "F.SilkS")
		)
		(fp_line
			(start 2.101 -1.6)
			(end -2.1 -1.6)
			(stroke
				(width 0.15)
				(type solid)
			)
			(layer "F.SilkS")
		)
		(fp_line
			(start 2.101 -1.58)
			(end 2.101 -1.459)
			(stroke
				(width 0.15)
				(type solid)
			)
			(layer "F.SilkS")
		)
		(fp_line
			(start 2.101 1.601)
			(end -2.1 1.601)
			(stroke
				(width 0.15)
				(type solid)
			)
			(layer "F.SilkS")
		)
		(fp_line
			(start 2.101 1.601)
			(end 2.101 1.48)
			(stroke
				(width 0.15)
				(type solid)
			)
			(layer "F.SilkS")
		)
		(fp_rect
			(start 2.751 1.75)
			(end -2.748 -1.749)
			(stroke
				(width 0.05)
				(type solid)
			)
			(fill none)
			(layer "F.CrtYd")
		)
		(fp_line
			(start -2.1 -1.6)
			(end -2.1 1.601)
			(stroke
				(width 0.15)
				(type solid)
			)
			(layer "F.Fab")
		)
		(fp_line
			(start -2.1 1.601)
			(end 2.101 1.601)
			(stroke
				(width 0.15)
				(type solid)
			)
			(layer "F.Fab")
		)
		(fp_line
			(start -0.248 -0.8)
			(end 0.25 -0.8)
			(stroke
				(width 0.15)
				(type solid)
			)
			(layer "F.Fab")
		)
		(fp_line
			(start 0.25 0.802)
			(end -0.248 0.802)
			(stroke
				(width 0.15)
				(type solid)
			)
			(layer "F.Fab")
		)
		(fp_line
			(start 2.101 -1.6)
			(end -2.1 -1.6)
			(stroke
				(width 0.15)
				(type solid)
			)
			(layer "F.Fab")
		)
		(fp_line
			(start 2.101 1.601)
			(end 2.101 -1.6)
			(stroke
				(width 0.15)
				(type solid)
			)
			(layer "F.Fab")
		)
		(fp_arc
			(start -0.248 0.802)
			(mid -1.050001 0.001)
			(end -0.248 -0.8)
			(stroke
				(width 0.15)
				(type solid)
			)
			(layer "F.Fab")
		)
		(fp_arc
			(start 0.25 -0.8)
			(mid 1.051001 0.001)
			(end 0.25 0.802)
			(stroke
				(width 0.15)
				(type solid)
			)
			(layer "F.Fab")
		)
		(fp_text user "${REFERENCE}"
			(at -3 4.25 0)
			(layer "F.Fab")
			(hide yes)
			(effects
				(font
					(size 0.7 0.7)
					(thickness 0.15)
				)
				(justify left bottom)
			)
		)
		(fp_text user "Author: Antmicro"
			(at -3 5.5 0)
			(layer "F.Fab")
			(hide yes)
			(effects
				(font
					(size 0.7 0.7)
					(thickness 0.15)
				)
				(justify left bottom)
			)
		)
		(fp_text user "License: Apache-2.0"
			(at -3 6.75 0)
			(layer "F.Fab")
			(hide yes)
			(effects
				(font
					(size 0.7 0.7)
					(thickness 0.15)
				)
				(justify left bottom)
			)
		)
		(pad "1" smd rect
			(at -2.048 -0.8 180)
			(size 0.9 1)
			(layers "F.Cu" "F.Paste" "F.Mask")
			(net 137 "Net-(D36-A)")
			(pinfunction "1")
			(pintype "passive")
		)
		(pad "2" smd rect
			(at 2.05 -0.8 180)
			(size 0.9 1)
			(layers "F.Cu" "F.Paste" "F.Mask")
			(net 137 "Net-(D36-A)")
			(pinfunction "2")
			(pintype "passive")
		)
		(pad "3" smd rect
			(at -2.048 0.802 180)
			(size 0.9 1)
			(layers "F.Cu" "F.Paste" "F.Mask")
			(net 1 "GND")
			(pinfunction "3")
			(pintype "passive")
		)
		(pad "4" smd rect
			(at 2.05 0.802 180)
			(size 0.9 1)
			(layers "F.Cu" "F.Paste" "F.Mask")
			(net 1 "GND")
			(pinfunction "4")
			(pintype "passive")
		)
	)
	(footprint "antmicro-footprints:R_0402_1005Metric"
		(layer "F.Cu")
		(at 48.3 105.3 90)
		(descr "Resistor SMD 0402")
		(tags "resistor SMD 0402")
		(property "Reference" "R286"
			(at -13 1.9 -90)
			(layer "F.SilkS")
			(effects
				(font
					(size 0.7 0.7)
					(thickness 0.15)
				)
				(justify left bottom)
			)
		)
		(property "Value" "R_470R_0402"
			(at -1.011843 1.772046 90)
			(layer "F.Fab")
			(effects
				(font
					(size 0.7 0.7)
					(thickness 0.15)
				)
				(justify left bottom)
			)
		)
		(property "Footprint" "antmicro-footprints:R_0402_1005Metric"
			(at 0 0 90)
			(layer "F.Fab")
			(hide yes)
			(effects
				(font
					(size 1.27 1.27)
					(thickness 0.15)
				)
			)
		)
		(property "Datasheet" "https://www.bourns.com/docs/product-datasheets/cr.pdf"
			(at 0 0 90)
			(layer "F.Fab")
			(hide yes)
			(effects
				(font
					(size 1.27 1.27)
					(thickness 0.15)
				)
			)
		)
		(property "Manufacturer" "Bourns"
			(at 0 0 90)
			(unlocked yes)
			(layer "F.Fab")
			(hide yes)
			(effects
				(font
					(size 1 1)
					(thickness 0.15)
				)
			)
		)
		(property "MPN" "CR0402-FX-4700GLF"
			(at 0 0 90)
			(unlocked yes)
			(layer "F.Fab")
			(hide yes)
			(effects
				(font
					(size 1 1)
					(thickness 0.15)
				)
			)
		)
		(property "Val" "470R"
			(at 0 0 90)
			(unlocked yes)
			(layer "F.Fab")
			(hide yes)
			(effects
				(font
					(size 1 1)
					(thickness 0.15)
				)
			)
		)
		(property "License" "Apache-2.0"
			(at 0 0 90)
			(unlocked yes)
			(layer "F.Fab")
			(hide yes)
			(effects
				(font
					(size 1 1)
					(thickness 0.15)
				)
			)
		)
		(property "Author" "Antmicro"
			(at 0 0 90)
			(unlocked yes)
			(layer "F.Fab")
			(hide yes)
			(effects
				(font
					(size 1 1)
					(thickness 0.15)
				)
			)
		)
		(property "Tolerance" "1%"
			(at 0 0 90)
			(unlocked yes)
			(layer "F.Fab")
			(hide yes)
			(effects
				(font
					(size 1 1)
					(thickness 0.15)
				)
			)
		)
		(sheetname "Supply")
		(sheetfile "supply.kicad_sch")
		(attr smd)
		(fp_poly
			(pts
				(xy -0.925 -0.47) (xy 0.925 -0.47) (xy 0.925 0.47) (xy -0.925 0.47)
			)
			(stroke
				(width 0.05)
				(type default)
			)
			(fill none)
			(layer "F.CrtYd")
		)
		(fp_poly
			(pts
				(xy -0.5 -0.25) (xy 0.5 -0.25) (xy 0.5 0.25) (xy -0.5 0.25)
			)
			(stroke
				(width 0.15)
				(type solid)
			)
			(fill none)
			(layer "F.Fab")
		)
		(fp_text user "${REFERENCE}"
			(at -0.95 3.168 90)
			(layer "F.Fab")
			(hide yes)
			(effects
				(font
					(size 0.7 0.7)
					(thickness 0.15)
				)
				(justify left bottom)
			)
		)
		(fp_text user "Author: Antmicro"
			(at -0.95 4.169 90)
			(layer "F.Fab")
			(hide yes)
			(effects
				(font
					(size 0.7 0.7)
					(thickness 0.15)
				)
				(justify left bottom)
			)
		)
		(fp_text user "License: Apache-2.0"
			(at -0.949999 5.169 90)
			(layer "F.Fab")
			(hide yes)
			(effects
				(font
					(size 0.7 0.7)
					(thickness 0.15)
				)
				(justify left bottom)
			)
		)
		(pad "1" smd roundrect
			(at -0.48 0 90)
			(size 0.59 0.64)
			(layers "F.Cu" "F.Paste" "F.Mask")
			(roundrect_rratio 0.25)
			(net 798 "Net-(D62-A)")
			(pintype "passive")
		)
		(pad "2" smd roundrect
			(at 0.48 0 90)
			(size 0.59 0.64)
			(layers "F.Cu" "F.Paste" "F.Mask")
			(roundrect_rratio 0.25)
			(net 787 "+5V_SoM")
			(pintype "passive")
		)
	)
)
